(kicad_pcb
	(version 20260206)
	(generator "pcbnew")
	(generator_version "10.0")
	(general
		(thickness 1.6)
		(legacy_teardrops no)
	)
	(paper "A4")
	(title_block
		(title "v2-pdb — ms_pdb_v2.brd")
		(comment 1 "Open CloudServer (Microsoft) / footprints 319-325 of 348")
	)
	(layers
		(0 "F.Cu" signal "TOP")
		(4 "In1.Cu" signal "GND")
		(6 "In2.Cu" signal "IN1")
		(8 "In3.Cu" signal "VCC")
		(10 "In4.Cu" signal "VCC1")
		(12 "In5.Cu" signal "IN2")
		(14 "In6.Cu" signal "GND1")
		(2 "B.Cu" signal "BOTTOM")
		(9 "F.Adhes" user "F.Adhesive")
		(11 "B.Adhes" user "B.Adhesive")
		(13 "F.Paste" user "Package Geometry/Pastemask Top")
		(15 "B.Paste" user "Package Geometry/Pastemask Bottom")
		(5 "F.SilkS" user "Ref Des/Silkscreen Top")
		(7 "B.SilkS" user "Ref Des/Silkscreen Bottom")
		(1 "F.Mask" user "Board Geometry/Soldermask Top")
		(3 "B.Mask" user "Board Geometry/Soldermask Bottom")
		(17 "Dwgs.User" user "User.Drawings")
		(19 "Cmts.User" user "User.Comments")
		(21 "Eco1.User" user "User.Eco1")
		(23 "Eco2.User" user "User.Eco2")
		(25 "Edge.Cuts" user "Board Geometry/Outline")
		(27 "Margin" user)
		(31 "F.CrtYd" user "Package Geometry/Place Bound Top")
		(29 "B.CrtYd" user "Package Geometry/Place Bound Bottom")
		(35 "F.Fab" user "Ref Des/Assembly Top")
		(33 "B.Fab" user "Ref Des/Assembly Bottom")
	)
	(footprint ""
		(layer "F.Cu")
		(at 71.871332 -286.474154 -90)
		(property "Reference" "C43"
			(at 0.298704 -4.020312 90)
			(unlocked yes)
			(layer "F.SilkS")
			(effects
				(font
					(size 0.7874 0.5842)
					(thickness 0.1524)
				)
			)
		)
		(property "Value" ""
			(at 0 0 270)
			(layer "F.Fab")
			(effects
				(font
					(size 1.27 1.27)
				)
			)
		)
		(duplicate_pad_numbers_are_jumpers no)
		(fp_line
			(start -1.2954 0.5842)
			(end -1.2954 -0.5842)
			(stroke
				(width 0.1524)
				(type default)
			)
			(layer "F.SilkS")
		)
		(fp_line
			(start 1.2954 0.5842)
			(end -1.2954 0.5842)
			(stroke
				(width 0.1524)
				(type default)
			)
			(layer "F.SilkS")
		)
		(fp_line
			(start -1.2954 -0.5842)
			(end 1.2954 -0.5842)
			(stroke
				(width 0.1524)
				(type default)
			)
			(layer "F.SilkS")
		)
		(fp_line
			(start 0 -0.5842)
			(end 0 0.5842)
			(stroke
				(width 0.1524)
				(type default)
			)
			(layer "F.SilkS")
		)
		(fp_line
			(start 1.2954 -0.5842)
			(end 1.2954 0.5842)
			(stroke
				(width 0.1524)
				(type default)
			)
			(layer "F.SilkS")
		)
		(fp_poly
			(pts
				(xy 0.8636 -0.4572) (xy 0.8636 -0.3556) (xy 1.143 -0.3556) (xy 1.143 0.3556) (xy 0.8636 0.3556)
				(xy 0.8636 0.4572) (xy -0.8636 0.4572) (xy -0.8636 0.3556) (xy -1.143 0.3556) (xy -1.143 -0.3556)
				(xy -0.8636 -0.3556) (xy -0.8636 -0.4572)
			)
			(stroke
				(width 0)
				(type default)
			)
			(fill no)
			(layer "F.CrtYd")
		)
		(fp_line
			(start -0.884936 0.504952)
			(end -0.884936 -0.504952)
			(stroke
				(width 0.1)
				(type default)
			)
			(layer "F.Fab")
		)
		(fp_line
			(start 0.884936 0.504952)
			(end -0.884936 0.504952)
			(stroke
				(width 0.1)
				(type default)
			)
			(layer "F.Fab")
		)
		(fp_line
			(start -0.884936 -0.504952)
			(end 0.884936 -0.504952)
			(stroke
				(width 0.1)
				(type default)
			)
			(layer "F.Fab")
		)
		(fp_line
			(start 0.884936 -0.504952)
			(end 0.884936 0.504952)
			(stroke
				(width 0.1)
				(type default)
			)
			(layer "F.Fab")
		)
		(pad "1" smd rect
			(at 0.7366 0)
			(size 0.7112 0.8128)
			(layers "F.Cu" "F.Mask" "F.Paste")
			(net "P12V")
		)
		(pad "2" smd rect
			(at -0.7366 0)
			(size 0.7112 0.8128)
			(layers "F.Cu" "F.Mask" "F.Paste")
			(net "GND")
		)
	)
	(footprint ""
		(layer "F.Cu")
		(at 26.103834 -189.265306 180)
		(property "Reference" "R51"
			(at 4.040632 -0.318516 0)
			(unlocked yes)
			(layer "F.SilkS")
			(effects
				(font
					(size 0.7874 0.5842)
					(thickness 0.1524)
				)
				(justify left)
			)
		)
		(property "Value" ""
			(at 0 0 180)
			(layer "F.Fab")
			(effects
				(font
					(size 1.27 1.27)
				)
			)
		)
		(duplicate_pad_numbers_are_jumpers no)
		(fp_line
			(start 0.7874 0.4064)
			(end -0.7874 0.4064)
			(stroke
				(width 0.1524)
				(type default)
			)
			(layer "F.SilkS")
		)
		(fp_line
			(start 0.7874 -0.4064)
			(end 0.7874 0.4064)
			(stroke
				(width 0.1524)
				(type default)
			)
			(layer "F.SilkS")
		)
		(fp_line
			(start -0.7874 0.4064)
			(end -0.7874 -0.4064)
			(stroke
				(width 0.1524)
				(type default)
			)
			(layer "F.SilkS")
		)
		(fp_line
			(start -0.7874 -0.4064)
			(end 0.7874 -0.4064)
			(stroke
				(width 0.1524)
				(type default)
			)
			(layer "F.SilkS")
		)
		(fp_poly
			(pts
				(xy -0.508 0.2794) (xy -0.508 0.2286) (xy -0.635 0.2286) (xy -0.635 -0.254) (xy -0.5334 -0.254)
				(xy -0.5334 -0.2794) (xy 0.5334 -0.2794) (xy 0.5334 -0.254) (xy 0.635 -0.254) (xy 0.635 0.254) (xy 0.5334 0.254)
				(xy 0.5334 0.2794)
			)
			(stroke
				(width 0)
				(type default)
			)
			(fill no)
			(layer "F.CrtYd")
		)
		(pad "1" smd rect
			(at 0.40005 0 180)
			(size 0.4572 0.508)
			(layers "F.Cu" "F.Mask" "F.Paste")
			(net "GND")
		)
		(pad "2" smd rect
			(at -0.40005 0 180)
			(size 0.4572 0.508)
			(layers "F.Cu" "F.Mask" "F.Paste")
			(net "PSU3_PS_ON_N")
		)
	)
	(footprint ""
		(layer "F.Cu")
		(at 50.54981 -507.67742 180)
		(property "Reference" "CE23"
			(at 2.73939 5.49021 0)
			(unlocked yes)
			(layer "F.SilkS")
			(effects
				(font
					(size 0.7874 0.5842)
					(thickness 0.1524)
				)
				(justify left)
			)
		)
		(property "Value" ""
			(at 0 0 180)
			(layer "F.Fab")
			(effects
				(font
					(size 1.27 1.27)
				)
			)
		)
		(duplicate_pad_numbers_are_jumpers no)
		(fp_line
			(start 0 -4.2672)
			(end 0 4.2672)
			(stroke
				(width 0.1524)
				(type default)
			)
			(layer "F.SilkS")
		)
		(fp_circle
			(center 0 0)
			(end -4.2672 0)
			(stroke
				(width 0.1524)
				(type default)
			)
			(fill no)
			(layer "F.SilkS")
		)
		(fp_poly
			(pts
				(arc
					(start 0 -4.2672)
					(mid 4.2672 0)
					(end 0 4.2672)
				)
			)
			(stroke
				(width 0)
				(type default)
			)
			(fill yes)
			(layer "F.SilkS")
		)
		(fp_poly
			(pts
				(xy -2.5146 -0.762) (xy -0.9906 -0.762) (xy -0.9906 0.762) (xy -2.5146 0.762)
			)
			(stroke
				(width 0)
				(type default)
			)
			(fill no)
			(layer "B.CrtYd")
		)
		(fp_poly
			(pts
				(arc
					(start 1.7526 0.762)
					(mid 2.291415 -0.538815)
					(end 0.9906 0)
				)
				(arc
					(start 0.9906 0.0254)
					(mid 1.206345 0.546255)
					(end 1.7272 0.762)
				)
			)
			(stroke
				(width 0)
				(type default)
			)
			(fill no)
			(layer "B.CrtYd")
		)
		(fp_poly
			(pts
				(arc
					(start -4.2672 0)
					(mid 4.2672 0)
					(end -4.2672 0)
				)
			)
			(stroke
				(width 0)
				(type default)
			)
			(fill no)
			(layer "F.CrtYd")
		)
		(fp_circle
			(center 0 0)
			(end -4.2672 0)
			(stroke
				(width 0.1)
				(type default)
			)
			(fill no)
			(layer "F.Fab")
		)
		(fp_text user "+"
			(at -5.619496 -0.34925 180)
			(unlocked yes)
			(layer "F.SilkS")
			(effects
				(font
					(size 1.905 1.4224)
					(thickness 0.1524)
				)
				(justify left)
			)
		)
		(fp_text user "+"
			(at -5.6642 -0.34925 180)
			(unlocked yes)
			(layer "F.Fab")
			(effects
				(font
					(size 1.905 1.4224)
					(thickness 0.000001)
				)
				(justify left)
			)
		)
		(pad "1" thru_hole rect
			(at -1.75006 0 180)
			(size 1.397 1.397)
			(drill 0.9144)
			(layers "*.Cu" "*.Mask")
			(remove_unused_layers no)
			(net "P12V")
			(clearance 0.0127)
			(thermal_gap 0.0127)
			(padstack
				(mode front_inner_back)
				(layer "Inner"
					(shape circle)
					(size 1.397 1.397)
					(clearance 0.0127)
				)
				(layer "B.Cu"
					(shape rect)
					(size 1.397 1.397)
					(clearance 0.0127)
				)
			)
		)
		(pad "2" thru_hole circle
			(at 1.75006 0 180)
			(size 1.397 1.397)
			(drill 0.9144)
			(layers "*.Cu" "*.Mask")
			(remove_unused_layers no)
			(net "GND")
			(clearance 0.0127)
			(thermal_gap 0.0127)
		)
	)
	(footprint ""
		(layer "F.Cu")
		(at 26.226008 -452.257668)
		(property "Reference" "R83"
			(at -3.522472 -0.815594 0)
			(unlocked yes)
			(layer "F.SilkS")
			(effects
				(font
					(size 0.7874 0.5842)
					(thickness 0.1524)
				)
				(justify left)
			)
		)
		(property "Value" ""
			(at 0 0 0)
			(layer "F.Fab")
			(effects
				(font
					(size 1.27 1.27)
				)
			)
		)
		(duplicate_pad_numbers_are_jumpers no)
		(fp_line
			(start -0.7874 -0.4064)
			(end 0.7874 -0.4064)
			(stroke
				(width 0.1524)
				(type default)
			)
			(layer "F.SilkS")
		)
		(fp_line
			(start -0.7874 0.4064)
			(end -0.7874 -0.4064)
			(stroke
				(width 0.1524)
				(type default)
			)
			(layer "F.SilkS")
		)
		(fp_line
			(start 0.7874 -0.4064)
			(end 0.7874 0.4064)
			(stroke
				(width 0.1524)
				(type default)
			)
			(layer "F.SilkS")
		)
		(fp_line
			(start 0.7874 0.4064)
			(end -0.7874 0.4064)
			(stroke
				(width 0.1524)
				(type default)
			)
			(layer "F.SilkS")
		)
		(fp_poly
			(pts
				(xy -0.508 0.2794) (xy -0.508 0.2286) (xy -0.635 0.2286) (xy -0.635 -0.254) (xy -0.5334 -0.254)
				(xy -0.5334 -0.2794) (xy 0.5334 -0.2794) (xy 0.5334 -0.254) (xy 0.635 -0.254) (xy 0.635 0.254) (xy 0.5334 0.254)
				(xy 0.5334 0.2794)
			)
			(stroke
				(width 0)
				(type default)
			)
			(fill no)
			(layer "F.CrtYd")
		)
		(pad "1" smd rect
			(at 0.40005 0)
			(size 0.4572 0.508)
			(layers "F.Cu" "F.Mask" "F.Paste")
			(net "PSU6_PS_KILL")
		)
		(pad "2" smd rect
			(at -0.40005 0)
			(size 0.4572 0.508)
			(layers "F.Cu" "F.Mask" "F.Paste")
			(net "GND")
		)
	)
	(footprint ""
		(layer "F.Cu")
		(at 66.823844 -38.821106 90)
		(property "Reference" "C14"
			(at 1.08712 -0.021082 90)
			(unlocked yes)
			(layer "F.SilkS")
			(effects
				(font
					(size 0.7874 0.5842)
					(thickness 0.1524)
				)
				(justify left)
			)
		)
		(property "Value" ""
			(at 0 0 90)
			(layer "F.Fab")
			(effects
				(font
					(size 1.27 1.27)
				)
			)
		)
		(duplicate_pad_numbers_are_jumpers no)
		(fp_line
			(start 0.7874 -0.4064)
			(end 0.7874 0.4064)
			(stroke
				(width 0.1524)
				(type default)
			)
			(layer "F.SilkS")
		)
		(fp_line
			(start -0.7874 -0.4064)
			(end 0.7874 -0.4064)
			(stroke
				(width 0.1524)
				(type default)
			)
			(layer "F.SilkS")
		)
		(fp_line
			(start 0 0.381)
			(end 0 -0.381)
			(stroke
				(width 0.1524)
				(type default)
			)
			(layer "F.SilkS")
		)
		(fp_line
			(start 0.7874 0.4064)
			(end -0.7874 0.4064)
			(stroke
				(width 0.1524)
				(type default)
			)
			(layer "F.SilkS")
		)
		(fp_line
			(start -0.7874 0.4064)
			(end -0.7874 -0.4064)
			(stroke
				(width 0.1524)
				(type default)
			)
			(layer "F.SilkS")
		)
		(fp_poly
			(pts
				(xy -0.5334 0.254) (xy -0.635 0.254) (xy -0.635 0.2286) (xy -0.635 -0.254) (xy -0.5334 -0.254) (xy -0.5334 -0.2794)
				(xy 0.5334 -0.2794) (xy 0.5334 -0.254) (xy 0.635 -0.254) (xy 0.635 0.254) (xy 0.5334 0.254) (xy 0.5334 0.2794)
				(xy -0.508 0.2794) (xy -0.5334 0.2794)
			)
			(stroke
				(width 0)
				(type default)
			)
			(fill no)
			(layer "F.CrtYd")
		)
		(pad "1" smd rect
			(at 0.40005 0 90)
			(size 0.4572 0.508)
			(layers "F.Cu" "F.Mask" "F.Paste")
			(net "P12V")
		)
		(pad "2" smd rect
			(at -0.40005 0 90)
			(size 0.4572 0.508)
			(layers "F.Cu" "F.Mask" "F.Paste")
			(net "GND")
		)
	)
	(footprint ""
		(layer "F.Cu")
		(at 26.068274 -181.847998)
		(property "Reference" "R73"
			(at -3.997198 0.128524 0)
			(unlocked yes)
			(layer "F.SilkS")
			(effects
				(font
					(size 0.7874 0.5842)
					(thickness 0.1524)
				)
				(justify left)
			)
		)
		(property "Value" ""
			(at 0 0 0)
			(layer "F.Fab")
			(effects
				(font
					(size 1.27 1.27)
				)
			)
		)
		(duplicate_pad_numbers_are_jumpers no)
		(fp_line
			(start -0.7874 -0.4064)
			(end 0.7874 -0.4064)
			(stroke
				(width 0.1524)
				(type default)
			)
			(layer "F.SilkS")
		)
		(fp_line
			(start -0.7874 0.4064)
			(end -0.7874 -0.4064)
			(stroke
				(width 0.1524)
				(type default)
			)
			(layer "F.SilkS")
		)
		(fp_line
			(start 0.7874 -0.4064)
			(end 0.7874 0.4064)
			(stroke
				(width 0.1524)
				(type default)
			)
			(layer "F.SilkS")
		)
		(fp_line
			(start 0.7874 0.4064)
			(end -0.7874 0.4064)
			(stroke
				(width 0.1524)
				(type default)
			)
			(layer "F.SilkS")
		)
		(fp_poly
			(pts
				(xy -0.508 0.2794) (xy -0.508 0.2286) (xy -0.635 0.2286) (xy -0.635 -0.254) (xy -0.5334 -0.254)
				(xy -0.5334 -0.2794) (xy 0.5334 -0.2794) (xy 0.5334 -0.254) (xy 0.635 -0.254) (xy 0.635 0.254) (xy 0.5334 0.254)
				(xy 0.5334 0.2794)
			)
			(stroke
				(width 0)
				(type default)
			)
			(fill no)
			(layer "F.CrtYd")
		)
		(pad "1" smd rect
			(at 0.40005 0)
			(size 0.4572 0.508)
			(layers "F.Cu" "F.Mask" "F.Paste")
			(net "PSU3_RESET")
		)
		(pad "2" smd rect
			(at -0.40005 0)
			(size 0.4572 0.508)
			(layers "F.Cu" "F.Mask" "F.Paste")
			(net "GND")
		)
	)
	(footprint ""
		(layer "B.Cu")
		(at 93.307916 -80.871314)
		(property "Reference" "U4"
			(at 4.759198 0.010414 0)
			(unlocked yes)
			(layer "B.SilkS")
			(effects
				(font
					(size 0.7874 0.5842)
					(thickness 0.1524)
				)
				(justify left mirror)
			)
		)
		(property "Value" ""
			(at 0 0 0)
			(layer "B.Fab")
			(effects
				(font
					(size 1.27 1.27)
				)
				(justify mirror)
			)
		)
		(duplicate_pad_numbers_are_jumpers no)
		(fp_line
			(start -2.5527 -2.0066)
			(end -2.5527 2.0066)
			(stroke
				(width 0.1524)
				(type default)
			)
			(layer "B.SilkS")
		)
		(fp_line
			(start -2.5527 2.0066)
			(end 2.5527 2.0066)
			(stroke
				(width 0.1524)
				(type default)
			)
			(layer "B.SilkS")
		)
		(fp_line
			(start 1.9812 0)
			(end 2.5527 -0.5715)
			(stroke
				(width 0.1524)
				(type default)
			)
			(layer "B.SilkS")
		)
		(fp_line
			(start 2.5527 -2.0066)
			(end -2.5527 -2.0066)
			(stroke
				(width 0.1524)
				(type default)
			)
			(layer "B.SilkS")
		)
		(fp_line
			(start 2.5527 -0.5715)
			(end 2.5527 -2.0066)
			(stroke
				(width 0.1524)
				(type default)
			)
			(layer "B.SilkS")
		)
		(fp_line
			(start 2.5527 0.5715)
			(end 1.9812 0)
			(stroke
				(width 0.1524)
				(type default)
			)
			(layer "B.SilkS")
		)
		(fp_line
			(start 2.5527 2.0066)
			(end 2.5527 0.5715)
			(stroke
				(width 0.1524)
				(type default)
			)
			(layer "B.SilkS")
		)
		(fp_circle
			(center 2.032 1.524)
			(end 2.286 1.524)
			(stroke
				(width 0.1524)
				(type default)
			)
			(fill no)
			(layer "B.SilkS")
		)
		(fp_rect
			(start 2.5527 3.6703)
			(end -2.5527 -3.6703)
			(stroke
				(width 0)
				(type default)
			)
			(fill no)
			(layer "B.CrtYd")
		)
		(fp_line
			(start -2.549906 -2.249932)
			(end -2.549906 2.249932)
			(stroke
				(width 0.1)
				(type default)
			)
			(layer "B.Fab")
		)
		(fp_line
			(start -2.549906 2.249932)
			(end 2.549906 2.249932)
			(stroke
				(width 0.1)
				(type default)
			)
			(layer "B.Fab")
		)
		(fp_line
			(start 2.549906 -2.249932)
			(end -2.549906 -2.249932)
			(stroke
				(width 0.1)
				(type default)
			)
			(layer "B.Fab")
		)
		(fp_line
			(start 2.549906 2.249932)
			(end 2.549906 -2.249932)
			(stroke
				(width 0.1)
				(type default)
			)
			(layer "B.Fab")
		)
		(pad "1" smd rect
			(at 1.949958 2.921 180)
			(size 0.3556 1.4986)
			(layers "B.Cu" "B.Mask" "B.Paste")
			(net "PSU_ALERT_N")
		)
		(pad "2" smd rect
			(at 1.299972 2.921 180)
			(size 0.3556 1.4986)
			(layers "B.Cu" "B.Mask" "B.Paste")
			(net "B1_PSU_ALERT_N")
		)
		(pad "3" smd rect
			(at 0.649986 2.921 180)
			(size 0.3556 1.4986)
			(layers "B.Cu" "B.Mask" "B.Paste")
			(net "PSU_ALERT_N")
		)
		(pad "4" smd rect
			(at 0 2.921 180)
			(size 0.3556 1.4986)
			(layers "B.Cu" "B.Mask" "B.Paste")
			(net "B2_PSU_ALERT_N")
		)
		(pad "5" smd rect
			(at -0.649986 2.921 180)
			(size 0.3556 1.4986)
			(layers "B.Cu" "B.Mask" "B.Paste")
			(net "PSU_ALERT_N")
		)
		(pad "6" smd rect
			(at -1.299972 2.921 180)
			(size 0.3556 1.4986)
			(layers "B.Cu" "B.Mask" "B.Paste")
			(net "B3_PSU_ALERT_N")
		)
		(pad "7" smd rect
			(at -1.949958 2.921 180)
			(size 0.3556 1.4986)
			(layers "B.Cu" "B.Mask" "B.Paste")
			(net "GND")
		)
		(pad "8" smd rect
			(at -1.949958 -2.921 180)
			(size 0.3556 1.4986)
			(layers "B.Cu" "B.Mask" "B.Paste")
			(net "B4_PSU_ALERT_N")
		)
		(pad "9" smd rect
			(at -1.299972 -2.921 180)
			(size 0.3556 1.4986)
			(layers "B.Cu" "B.Mask" "B.Paste")
			(net "PSU_ALERT_N")
		)
		(pad "10" smd rect
			(at -0.649986 -2.921 180)
			(size 0.3556 1.4986)
			(layers "B.Cu" "B.Mask" "B.Paste")
			(net "B5_PSU_ALERT_N")
		)
		(pad "11" smd rect
			(at 0 -2.921 180)
			(size 0.3556 1.4986)
			(layers "B.Cu" "B.Mask" "B.Paste")
			(net "PSU_ALERT_N")
		)
		(pad "12" smd rect
			(at 0.649986 -2.921 180)
			(size 0.3556 1.4986)
			(layers "B.Cu" "B.Mask" "B.Paste")
			(net "B6_PSU_ALERT_N")
		)
		(pad "13" smd rect
			(at 1.299972 -2.921 180)
			(size 0.3556 1.4986)
			(layers "B.Cu" "B.Mask" "B.Paste")
			(net "PSU_ALERT_N")
		)
		(pad "14" smd rect
			(at 1.949958 -2.921 180)
			(size 0.3556 1.4986)
			(layers "B.Cu" "B.Mask" "B.Paste")
			(net "P3V3_BUF")
		)
	)
)
